(kicad_pcb
	(version 20260206)
	(generator "pcbnew")
	(generator_version "10.0")
	(general
		(thickness 1.6)
		(legacy_teardrops no)
	)
	(paper "A4")
	(title_block
		(title "9054_F0T_PDB_BD_GPU_F_V04_1213_1550_OCP.brd")
		(comment 1 "Grand Teton / footprints 423-427 of 608")
	)
	(layers
		(0 "F.Cu" signal "TOP")
		(4 "In1.Cu" signal "GND")
		(6 "In2.Cu" signal "IN1")
		(8 "In3.Cu" signal "GND1")
		(10 "In4.Cu" signal "VCC")
		(12 "In5.Cu" signal "VCC1")
		(14 "In6.Cu" signal "GND2")
		(16 "In7.Cu" signal "IN2")
		(18 "In8.Cu" signal "GND3")
		(2 "B.Cu" signal "BOTTOM")
		(9 "F.Adhes" user "F.Adhesive")
		(11 "B.Adhes" user "B.Adhesive")
		(13 "F.Paste" user "Package Geometry/Pastemask Top")
		(15 "B.Paste" user "Package Geometry/Pastemask Bottom")
		(5 "F.SilkS" user "Ref Des/Silkscreen Top")
		(7 "B.SilkS" user "Ref Des/Silkscreen Bottom")
		(1 "F.Mask" user "Board Geometry/Soldermask Top")
		(3 "B.Mask" user "Board Geometry/Soldermask Bottom")
		(17 "Dwgs.User" user "User.Drawings")
		(19 "Cmts.User" user "User.Comments")
		(21 "Eco1.User" user "User.Eco1")
		(23 "Eco2.User" user "User.Eco2")
		(25 "Edge.Cuts" user "Board Geometry/Outline")
		(27 "Margin" user)
		(31 "F.CrtYd" user "Package Geometry/Place Bound Top")
		(29 "B.CrtYd" user "Package Geometry/Place Bound Bottom")
		(35 "F.Fab" user "Ref Des/Assembly Top")
		(33 "B.Fab" user "Ref Des/Assembly Bottom")
	)
	(footprint ""
		(layer "B.Cu")
		(at 255.778 -52.832 90)
		(property "Reference" "PD7"
			(at 5.08 2.64033 270)
			(unlocked yes)
			(layer "B.SilkS")
			(effects
				(font
					(size 0.7874 0.5842)
					(thickness 0.1524)
				)
				(justify left mirror)
			)
		)
		(property "Value" ""
			(at 0 0 90)
			(layer "B.Fab")
			(effects
				(font
					(size 1.27 1.27)
				)
				(justify mirror)
			)
		)
		(duplicate_pad_numbers_are_jumpers no)
		(fp_line
			(start 4.664456 -3.109976)
			(end -4.743704 -3.109976)
			(stroke
				(width 0.1524)
				(type default)
			)
			(layer "B.SilkS")
		)
		(fp_line
			(start -4.183126 -3.109976)
			(end -4.794504 -3.109976)
			(stroke
				(width 0.1524)
				(type default)
			)
			(layer "B.SilkS")
		)
		(fp_line
			(start -4.511802 -3.109976)
			(end -4.207002 -3.109976)
			(stroke
				(width 0.1524)
				(type default)
			)
			(layer "B.SilkS")
		)
		(fp_line
			(start -4.6101 -3.109976)
			(end -4.283202 -3.109976)
			(stroke
				(width 0.1524)
				(type default)
			)
			(layer "B.SilkS")
		)
		(fp_line
			(start -4.695444 -3.109976)
			(end -4.695444 3.109976)
			(stroke
				(width 0.1524)
				(type default)
			)
			(layer "B.SilkS")
		)
		(fp_line
			(start -4.70535 -3.109976)
			(end -4.70535 3.109976)
			(stroke
				(width 0.1524)
				(type default)
			)
			(layer "B.SilkS")
		)
		(fp_line
			(start -4.70535 -3.109976)
			(end -4.70535 3.109976)
			(stroke
				(width 0.1524)
				(type default)
			)
			(layer "B.SilkS")
		)
		(fp_line
			(start -4.70535 -3.109976)
			(end -4.70535 3.109976)
			(stroke
				(width 0.1524)
				(type default)
			)
			(layer "B.SilkS")
		)
		(fp_line
			(start -4.805426 -3.109976)
			(end -4.805426 3.109976)
			(stroke
				(width 0.1524)
				(type default)
			)
			(layer "B.SilkS")
		)
		(fp_line
			(start -4.932426 -3.109976)
			(end -4.932426 3.109976)
			(stroke
				(width 0.1524)
				(type default)
			)
			(layer "B.SilkS")
		)
		(fp_line
			(start -5.008626 -3.109976)
			(end -5.008626 3.109976)
			(stroke
				(width 0.1524)
				(type default)
			)
			(layer "B.SilkS")
		)
		(fp_line
			(start -5.110226 -3.109976)
			(end -5.110226 3.109976)
			(stroke
				(width 0.1524)
				(type default)
			)
			(layer "B.SilkS")
		)
		(fp_line
			(start -5.211826 -3.109976)
			(end -5.211826 3.109976)
			(stroke
				(width 0.1524)
				(type default)
			)
			(layer "B.SilkS")
		)
		(fp_line
			(start -5.262626 -3.109976)
			(end -5.262626 3.109976)
			(stroke
				(width 0.1524)
				(type default)
			)
			(layer "B.SilkS")
		)
		(fp_line
			(start -5.313426 -3.109976)
			(end -5.313426 1.0414)
			(stroke
				(width 0.1524)
				(type default)
			)
			(layer "B.SilkS")
		)
		(fp_line
			(start -5.4102 -3.109976)
			(end -4.783074 -3.109976)
			(stroke
				(width 0.1524)
				(type default)
			)
			(layer "B.SilkS")
		)
		(fp_line
			(start 0.508 -1.016)
			(end -0.762 0)
			(stroke
				(width 0.1524)
				(type default)
			)
			(layer "B.SilkS")
		)
		(fp_line
			(start 1.0668 0)
			(end 0.6096 0)
			(stroke
				(width 0.1524)
				(type default)
			)
			(layer "B.SilkS")
		)
		(fp_line
			(start -0.762 0)
			(end -1.2192 0)
			(stroke
				(width 0.1524)
				(type default)
			)
			(layer "B.SilkS")
		)
		(fp_line
			(start -0.762 0)
			(end 0.508 1.016)
			(stroke
				(width 0.1524)
				(type default)
			)
			(layer "B.SilkS")
		)
		(fp_line
			(start 0.508 1.016)
			(end 0.508 -1.016)
			(stroke
				(width 0.1524)
				(type default)
			)
			(layer "B.SilkS")
		)
		(fp_line
			(start -5.4102 1.0668)
			(end -5.4102 -3.109976)
			(stroke
				(width 0.1524)
				(type default)
			)
			(layer "B.SilkS")
		)
		(fp_line
			(start -0.762 1.27)
			(end -0.762 -1.27)
			(stroke
				(width 0.1524)
				(type default)
			)
			(layer "B.SilkS")
		)
		(fp_line
			(start -5.313426 2.032)
			(end -5.313426 3.109976)
			(stroke
				(width 0.1524)
				(type default)
			)
			(layer "B.SilkS")
		)
		(fp_line
			(start -4.715002 3.035554)
			(end -4.7117 2.984754)
			(stroke
				(width 0.1524)
				(type default)
			)
			(layer "B.SilkS")
		)
		(fp_line
			(start 4.664456 3.109976)
			(end 4.664456 -3.109976)
			(stroke
				(width 0.1524)
				(type default)
			)
			(layer "B.SilkS")
		)
		(fp_line
			(start -4.156202 3.109976)
			(end -4.183126 3.109976)
			(stroke
				(width 0.1524)
				(type default)
			)
			(layer "B.SilkS")
		)
		(fp_line
			(start -4.743704 3.109976)
			(end -4.6101 3.109976)
			(stroke
				(width 0.1524)
				(type default)
			)
			(layer "B.SilkS")
		)
		(fp_line
			(start -4.743704 3.109976)
			(end -5.4102 3.109976)
			(stroke
				(width 0.1524)
				(type default)
			)
			(layer "B.SilkS")
		)
		(fp_line
			(start -4.769104 3.109976)
			(end 4.664456 3.109976)
			(stroke
				(width 0.1524)
				(type default)
			)
			(layer "B.SilkS")
		)
		(fp_line
			(start -4.794504 3.109976)
			(end -3.554984 3.109976)
			(stroke
				(width 0.1524)
				(type default)
			)
			(layer "B.SilkS")
		)
		(fp_line
			(start -5.4102 3.109976)
			(end -5.4102 1.9558)
			(stroke
				(width 0.1524)
				(type default)
			)
			(layer "B.SilkS")
		)
		(fp_line
			(start 4.065016 -3.109976)
			(end -4.065016 -3.109976)
			(stroke
				(width 0.1)
				(type default)
			)
			(layer "B.Fab")
		)
		(fp_line
			(start -4.065016 -3.109976)
			(end -4.065016 3.109976)
			(stroke
				(width 0.1)
				(type default)
			)
			(layer "B.Fab")
		)
		(fp_line
			(start 4.065016 3.109976)
			(end 4.065016 -3.109976)
			(stroke
				(width 0.1)
				(type default)
			)
			(layer "B.Fab")
		)
		(fp_line
			(start -4.065016 3.109976)
			(end 4.065016 3.109976)
			(stroke
				(width 0.1)
				(type default)
			)
			(layer "B.Fab")
		)
		(fp_text user "+"
			(at 6.1976 0.37465 270)
			(unlocked yes)
			(layer "B.SilkS")
			(effects
				(font
					(size 1.905 1.4224)
					(thickness 0.1524)
				)
				(justify left mirror)
			)
		)
		(fp_text user "-"
			(at -7.405624 0.65405 270)
			(unlocked yes)
			(layer "B.SilkS")
			(effects
				(font
					(size 1.905 1.4224)
					(thickness 0.1524)
				)
				(justify left mirror)
			)
		)
		(fp_text user "+"
			(at 4.5974 0.24765 270)
			(unlocked yes)
			(layer "B.Fab")
			(effects
				(font
					(size 1.905 1.4224)
					(thickness 0.1524)
				)
				(justify left mirror)
			)
		)
		(fp_text user "-"
			(at -6.643624 0.40005 270)
			(unlocked yes)
			(layer "B.Fab")
			(effects
				(font
					(size 1.905 1.4224)
					(thickness 0.1524)
				)
				(justify left mirror)
			)
		)
		(pad "A" smd rect
			(at 3.299968 0 90)
			(size 2.413 3.302)
			(layers "B.Cu" "B.Mask" "B.Paste")
			(net "GND")
		)
		(pad "C" smd rect
			(at -3.299968 0 90)
			(size 2.413 3.302)
			(layers "B.Cu" "B.Mask" "B.Paste")
			(net "P52V_1_FUSE_1")
		)
	)
	(footprint ""
		(layer "B.Cu")
		(at 271.4244 -76.454)
		(property "Reference" "PC589"
			(at 0 0 0)
			(layer "B.SilkS")
			(hide yes)
			(effects
				(font
					(size 1.27 1.27)
				)
				(justify mirror)
			)
		)
		(property "Value" ""
			(at 0 0 0)
			(layer "B.Fab")
			(effects
				(font
					(size 1.27 1.27)
				)
				(justify mirror)
			)
		)
		(duplicate_pad_numbers_are_jumpers no)
		(fp_line
			(start -0.7874 -0.4064)
			(end -0.7874 0.4064)
			(stroke
				(width 0.1524)
				(type default)
			)
			(layer "B.SilkS")
		)
		(fp_line
			(start -0.7874 0.4064)
			(end 0.7874 0.4064)
			(stroke
				(width 0.1524)
				(type default)
			)
			(layer "B.SilkS")
		)
		(fp_line
			(start 0.7874 -0.4064)
			(end -0.7874 -0.4064)
			(stroke
				(width 0.1524)
				(type default)
			)
			(layer "B.SilkS")
		)
		(fp_line
			(start 0.7874 0.4064)
			(end 0.7874 -0.4064)
			(stroke
				(width 0.1524)
				(type default)
			)
			(layer "B.SilkS")
		)
		(fp_line
			(start -0.67945 -0.3048)
			(end -0.67945 0.3048)
			(stroke
				(width 0.1)
				(type default)
			)
			(layer "B.Fab")
		)
		(fp_line
			(start -0.67945 0.3048)
			(end -0.120396 0.3048)
			(stroke
				(width 0.1)
				(type default)
			)
			(layer "B.Fab")
		)
		(fp_line
			(start -0.12065 -0.3048)
			(end -0.67945 -0.3048)
			(stroke
				(width 0.1)
				(type default)
			)
			(layer "B.Fab")
		)
		(fp_line
			(start -0.12065 -0.2794)
			(end -0.12065 -0.3048)
			(stroke
				(width 0.1)
				(type default)
			)
			(layer "B.Fab")
		)
		(fp_line
			(start -0.120396 0.2794)
			(end 0.12065 0.2794)
			(stroke
				(width 0.1)
				(type default)
			)
			(layer "B.Fab")
		)
		(fp_line
			(start -0.120396 0.3048)
			(end -0.120396 0.2794)
			(stroke
				(width 0.1)
				(type default)
			)
			(layer "B.Fab")
		)
		(fp_line
			(start 0.12065 -0.305054)
			(end 0.12065 -0.2794)
			(stroke
				(width 0.1)
				(type default)
			)
			(layer "B.Fab")
		)
		(fp_line
			(start 0.12065 -0.2794)
			(end -0.12065 -0.2794)
			(stroke
				(width 0.1)
				(type default)
			)
			(layer "B.Fab")
		)
		(fp_line
			(start 0.12065 0.2794)
			(end 0.12065 0.3048)
			(stroke
				(width 0.1)
				(type default)
			)
			(layer "B.Fab")
		)
		(fp_line
			(start 0.12065 0.3048)
			(end 0.67945 0.3048)
			(stroke
				(width 0.1)
				(type default)
			)
			(layer "B.Fab")
		)
		(fp_line
			(start 0.67945 -0.305054)
			(end 0.12065 -0.305054)
			(stroke
				(width 0.1)
				(type default)
			)
			(layer "B.Fab")
		)
		(fp_line
			(start 0.67945 0.3048)
			(end 0.67945 -0.305054)
			(stroke
				(width 0.1)
				(type default)
			)
			(layer "B.Fab")
		)
		(pad "1" smd circle
			(at 0.40005 0 180)
			(size 0 0)
			(layers "B.Cu" "B.Mask" "B.Paste")
			(net "P52V_HS1_TEMPP")
		)
		(pad "2" smd circle
			(at -0.40005 0 180)
			(size 0 0)
			(layers "B.Cu" "B.Mask" "B.Paste")
			(net "P52V_HS1_TEMPN")
		)
	)
	(footprint ""
		(layer "B.Cu")
		(at 341.5792 -49.9364 -90)
		(property "Reference" "PR220"
			(at 0 0 90)
			(layer "B.SilkS")
			(hide yes)
			(effects
				(font
					(size 1.27 1.27)
				)
				(justify mirror)
			)
		)
		(property "Value" ""
			(at 0 0 90)
			(layer "B.Fab")
			(effects
				(font
					(size 1.27 1.27)
				)
				(justify mirror)
			)
		)
		(duplicate_pad_numbers_are_jumpers no)
		(fp_line
			(start -1.2954 0.5842)
			(end 1.2954 0.5842)
			(stroke
				(width 0.1524)
				(type default)
			)
			(layer "B.SilkS")
		)
		(fp_line
			(start 1.2954 0.5842)
			(end 1.2954 -0.5842)
			(stroke
				(width 0.1524)
				(type default)
			)
			(layer "B.SilkS")
		)
		(fp_line
			(start -1.2954 -0.5842)
			(end -1.2954 0.5842)
			(stroke
				(width 0.1524)
				(type default)
			)
			(layer "B.SilkS")
		)
		(fp_line
			(start 1.2954 -0.5842)
			(end -1.2954 -0.5842)
			(stroke
				(width 0.1524)
				(type default)
			)
			(layer "B.SilkS")
		)
		(fp_line
			(start -0.8636 0.4572)
			(end 0.8636 0.4572)
			(stroke
				(width 0.1)
				(type default)
			)
			(layer "B.Fab")
		)
		(fp_line
			(start 0.8636 0.4572)
			(end 0.8636 0.4318)
			(stroke
				(width 0.1)
				(type default)
			)
			(layer "B.Fab")
		)
		(fp_line
			(start 0.8636 0.4318)
			(end 0.8636 0.4064)
			(stroke
				(width 0.1)
				(type default)
			)
			(layer "B.Fab")
		)
		(fp_line
			(start -1.1938 0.4064)
			(end -0.8636 0.4064)
			(stroke
				(width 0.1)
				(type default)
			)
			(layer "B.Fab")
		)
		(fp_line
			(start -0.8636 0.4064)
			(end -0.8636 0.4572)
			(stroke
				(width 0.1)
				(type default)
			)
			(layer "B.Fab")
		)
		(fp_line
			(start 0.8636 0.4064)
			(end 1.1938 0.4064)
			(stroke
				(width 0.1)
				(type default)
			)
			(layer "B.Fab")
		)
		(fp_line
			(start 1.1938 0.4064)
			(end 1.1938 -0.406654)
			(stroke
				(width 0.1)
				(type default)
			)
			(layer "B.Fab")
		)
		(fp_line
			(start -1.1938 -0.406654)
			(end -1.1938 0.4064)
			(stroke
				(width 0.1)
				(type default)
			)
			(layer "B.Fab")
		)
		(fp_line
			(start -0.8636 -0.406654)
			(end -1.1938 -0.406654)
			(stroke
				(width 0.1)
				(type default)
			)
			(layer "B.Fab")
		)
		(fp_line
			(start 0.8636 -0.406654)
			(end 0.8636 -0.4572)
			(stroke
				(width 0.1)
				(type default)
			)
			(layer "B.Fab")
		)
		(fp_line
			(start 1.1938 -0.406654)
			(end 0.8636 -0.406654)
			(stroke
				(width 0.1)
				(type default)
			)
			(layer "B.Fab")
		)
		(fp_line
			(start -0.8636 -0.4572)
			(end -0.8636 -0.406654)
			(stroke
				(width 0.1)
				(type default)
			)
			(layer "B.Fab")
		)
		(fp_line
			(start 0.8636 -0.4572)
			(end -0.8636 -0.4572)
			(stroke
				(width 0.1)
				(type default)
			)
			(layer "B.Fab")
		)
		(pad "1" smd rect
			(at 0.7366 0 180)
			(size 0.7112 0.8128)
			(layers "B.Cu" "B.Mask" "B.Paste")
			(net "P52V_HS1_4287_GATE_R")
		)
		(pad "2" smd rect
			(at -0.7366 0 180)
			(size 0.7112 0.8128)
			(layers "B.Cu" "B.Mask" "B.Paste")
			(net "P52V_HS1_GATE_RC")
		)
	)
	(footprint ""
		(layer "B.Cu")
		(at 341.63 -36.068 90)
		(property "Reference" "PC581"
			(at 0 0 90)
			(layer "B.SilkS")
			(hide yes)
			(effects
				(font
					(size 1.27 1.27)
				)
				(justify mirror)
			)
		)
		(property "Value" ""
			(at 0 0 90)
			(layer "B.Fab")
			(effects
				(font
					(size 1.27 1.27)
				)
				(justify mirror)
			)
		)
		(duplicate_pad_numbers_are_jumpers no)
		(fp_line
			(start 1.2954 -0.5842)
			(end -1.2954 -0.5842)
			(stroke
				(width 0.1524)
				(type default)
			)
			(layer "B.SilkS")
		)
		(fp_line
			(start -1.2954 -0.5842)
			(end -1.2954 0.5842)
			(stroke
				(width 0.1524)
				(type default)
			)
			(layer "B.SilkS")
		)
		(fp_line
			(start 1.2954 0.5842)
			(end 1.2954 -0.5842)
			(stroke
				(width 0.1524)
				(type default)
			)
			(layer "B.SilkS")
		)
		(fp_line
			(start -1.2954 0.5842)
			(end 1.2954 0.5842)
			(stroke
				(width 0.1524)
				(type default)
			)
			(layer "B.SilkS")
		)
		(fp_line
			(start 0.8636 -0.4572)
			(end -0.8636 -0.4572)
			(stroke
				(width 0.1)
				(type default)
			)
			(layer "B.Fab")
		)
		(fp_line
			(start -0.8636 -0.4572)
			(end -0.8636 -0.4064)
			(stroke
				(width 0.1)
				(type default)
			)
			(layer "B.Fab")
		)
		(fp_line
			(start 1.1938 -0.4064)
			(end 0.8636 -0.4064)
			(stroke
				(width 0.1)
				(type default)
			)
			(layer "B.Fab")
		)
		(fp_line
			(start 0.8636 -0.4064)
			(end 0.8636 -0.4572)
			(stroke
				(width 0.1)
				(type default)
			)
			(layer "B.Fab")
		)
		(fp_line
			(start -0.8636 -0.4064)
			(end -1.1938 -0.4064)
			(stroke
				(width 0.1)
				(type default)
			)
			(layer "B.Fab")
		)
		(fp_line
			(start -1.1938 -0.4064)
			(end -1.1938 0.4064)
			(stroke
				(width 0.1)
				(type default)
			)
			(layer "B.Fab")
		)
		(fp_line
			(start 1.1938 0.4064)
			(end 1.1938 -0.4064)
			(stroke
				(width 0.1)
				(type default)
			)
			(layer "B.Fab")
		)
		(fp_line
			(start 0.8636 0.4064)
			(end 1.1938 0.4064)
			(stroke
				(width 0.1)
				(type default)
			)
			(layer "B.Fab")
		)
		(fp_line
			(start -0.8636 0.4064)
			(end -0.8636 0.4572)
			(stroke
				(width 0.1)
				(type default)
			)
			(layer "B.Fab")
		)
		(fp_line
			(start -1.1938 0.4064)
			(end -0.8636 0.4064)
			(stroke
				(width 0.1)
				(type default)
			)
			(layer "B.Fab")
		)
		(fp_line
			(start 0.8636 0.4572)
			(end 0.8636 0.4064)
			(stroke
				(width 0.1)
				(type default)
			)
			(layer "B.Fab")
		)
		(fp_line
			(start -0.8636 0.4572)
			(end 0.8636 0.4572)
			(stroke
				(width 0.1)
				(type default)
			)
			(layer "B.Fab")
		)
		(pad "1" smd rect
			(at 0.7366 0)
			(size 0.7112 0.8128)
			(layers "B.Cu" "B.Mask" "B.Paste")
			(net "P52V_HS1_4287_GATE2_R")
		)
		(pad "2" smd rect
			(at -0.7366 0)
			(size 0.7112 0.8128)
			(layers "B.Cu" "B.Mask" "B.Paste")
			(net "P52V_HS1")
		)
	)
	(footprint ""
		(layer "B.Cu")
		(at 285.9024 -70.739 180)
		(property "Reference" "PR209"
			(at 0 0 0)
			(layer "B.SilkS")
			(hide yes)
			(effects
				(font
					(size 1.27 1.27)
				)
				(justify mirror)
			)
		)
		(property "Value" ""
			(at 0 0 0)
			(layer "B.Fab")
			(effects
				(font
					(size 1.27 1.27)
				)
				(justify mirror)
			)
		)
		(duplicate_pad_numbers_are_jumpers no)
		(fp_line
			(start 0.7874 0.4064)
			(end 0.7874 -0.4064)
			(stroke
				(width 0.1524)
				(type default)
			)
			(layer "B.SilkS")
		)
		(fp_line
			(start 0.7874 -0.4064)
			(end -0.7874 -0.4064)
			(stroke
				(width 0.1524)
				(type default)
			)
			(layer "B.SilkS")
		)
		(fp_line
			(start -0.7874 0.4064)
			(end 0.7874 0.4064)
			(stroke
				(width 0.1524)
				(type default)
			)
			(layer "B.SilkS")
		)
		(fp_line
			(start -0.7874 -0.4064)
			(end -0.7874 0.4064)
			(stroke
				(width 0.1524)
				(type default)
			)
			(layer "B.SilkS")
		)
		(fp_line
			(start 0.67945 0.3048)
			(end 0.67945 -0.305054)
			(stroke
				(width 0.1)
				(type default)
			)
			(layer "B.Fab")
		)
		(fp_line
			(start 0.67945 -0.305054)
			(end 0.12065 -0.305054)
			(stroke
				(width 0.1)
				(type default)
			)
			(layer "B.Fab")
		)
		(fp_line
			(start 0.12065 0.3048)
			(end 0.67945 0.3048)
			(stroke
				(width 0.1)
				(type default)
			)
			(layer "B.Fab")
		)
		(fp_line
			(start 0.12065 0.2794)
			(end 0.12065 0.3048)
			(stroke
				(width 0.1)
				(type default)
			)
			(layer "B.Fab")
		)
		(fp_line
			(start 0.12065 -0.2794)
			(end -0.12065 -0.2794)
			(stroke
				(width 0.1)
				(type default)
			)
			(layer "B.Fab")
		)
		(fp_line
			(start 0.12065 -0.305054)
			(end 0.12065 -0.2794)
			(stroke
				(width 0.1)
				(type default)
			)
			(layer "B.Fab")
		)
		(fp_line
			(start -0.120396 0.3048)
			(end -0.120396 0.2794)
			(stroke
				(width 0.1)
				(type default)
			)
			(layer "B.Fab")
		)
		(fp_line
			(start -0.120396 0.2794)
			(end 0.12065 0.2794)
			(stroke
				(width 0.1)
				(type default)
			)
			(layer "B.Fab")
		)
		(fp_line
			(start -0.12065 -0.2794)
			(end -0.12065 -0.3048)
			(stroke
				(width 0.1)
				(type default)
			)
			(layer "B.Fab")
		)
		(fp_line
			(start -0.12065 -0.3048)
			(end -0.67945 -0.3048)
			(stroke
				(width 0.1)
				(type default)
			)
			(layer "B.Fab")
		)
		(fp_line
			(start -0.67945 0.3048)
			(end -0.120396 0.3048)
			(stroke
				(width 0.1)
				(type default)
			)
			(layer "B.Fab")
		)
		(fp_line
			(start -0.67945 -0.3048)
			(end -0.67945 0.3048)
			(stroke
				(width 0.1)
				(type default)
			)
			(layer "B.Fab")
		)
		(pad "1" smd circle
			(at 0.40005 0)
			(size 0 0)
			(layers "B.Cu" "B.Mask" "B.Paste")
			(net "GND_FIELD_SIGNAL")
		)
		(pad "2" smd circle
			(at -0.40005 0)
			(size 0 0)
			(layers "B.Cu" "B.Mask" "B.Paste")
			(net "P52V_HS1_CS")
		)
	)
)
